# S9S_MB_2U (Grand Teton) — schematic netlist excerpt (pin names and nets, part order shuffled) for the footprints in the layout excerpt that follows; sources: Cadence DE-HDL packaged netlist, KiCad conversion of 03242023_DA0F0TMBIJ0_F0T_Motherboard_J_brd_V01_OCP.brd

R4547  Q_RES  100K 1% EMPTY  pkg 0402LF  page 145 : A = P3V3_AUX ; B = SWB_HSC_EN
R3783  Q_RES  100K 1% CHIP  pkg 0402LF  page 156 : A = P3V3_AUX ; B = OCP_V3_1_P3V3_PWRGD
C1519  Q_CAP_DIFFBUS  DIFF BUS_0.22UF 6.3V 20% X6S  pkg C0201  page 177 : \1\ = P5E_CPU1_PE3_TX_C_DP<14> ; \2\ = P5E_CPU1_PE3_TX_DP<14>

(kicad_pcb
	(version 20260206)
	(generator "pcbnew")
	(generator_version "10.0")
	(general
		(thickness 1.6)
		(legacy_teardrops no)
	)
	(paper "A4")
	(title_block
		(title "03242023_DA0F0TMBIJ0_F0T_Motherboard_J_brd_V01_OCP.brd")
		(comment 1 "Grand Teton / footprints 1102-1104 of 6105")
	)
	(layers
		(0 "F.Cu" signal "TOP")
		(4 "In1.Cu" signal "GND")
		(6 "In2.Cu" signal "IN1")
		(8 "In3.Cu" signal "GND1")
		(10 "In4.Cu" signal "IN2")
		(12 "In5.Cu" signal "GND2")
		(14 "In6.Cu" signal "IN3")
		(16 "In7.Cu" signal "GND3")
		(18 "In8.Cu" signal "VCC")
		(20 "In9.Cu" signal "VCC1")
		(22 "In10.Cu" signal "GND4")
		(24 "In11.Cu" signal "IN4")
		(26 "In12.Cu" signal "GND5")
		(28 "In13.Cu" signal "IN5")
		(30 "In14.Cu" signal "GND6")
		(32 "In15.Cu" signal "IN6")
		(34 "In16.Cu" signal "GND7")
		(2 "B.Cu" signal "BOTTOM")
		(9 "F.Adhes" user "F.Adhesive")
		(11 "B.Adhes" user "B.Adhesive")
		(13 "F.Paste" user "Package Geometry/Pastemask Top")
		(15 "B.Paste" user "Package Geometry/Pastemask Bottom")
		(5 "F.SilkS" user "Ref Des/Silkscreen Top")
		(7 "B.SilkS" user "Ref Des/Silkscreen Bottom")
		(1 "F.Mask" user "Board Geometry/Soldermask Top")
		(3 "B.Mask" user "Board Geometry/Soldermask Bottom")
		(17 "Dwgs.User" user "User.Drawings")
		(19 "Cmts.User" user "User.Comments")
		(21 "Eco1.User" user "User.Eco1")
		(23 "Eco2.User" user "User.Eco2")
		(25 "Edge.Cuts" user "Board Geometry/Outline")
		(27 "Margin" user)
		(31 "F.CrtYd" user "Package Geometry/Place Bound Top")
		(29 "B.CrtYd" user "Package Geometry/Place Bound Bottom")
		(35 "F.Fab" user "Ref Des/Assembly Top")
		(33 "B.Fab" user "Ref Des/Assembly Bottom")
	)
	(footprint ""
		(layer "F.Cu")
		(at 356.28072 -406.850088 90)
		(property "Reference" "R4547"
			(at 0 0 90)
			(layer "F.SilkS")
			(hide yes)
			(effects
				(font
					(size 1.27 1.27)
				)
			)
		)
		(property "Value" ""
			(at 0 0 90)
			(layer "F.Fab")
			(effects
				(font
					(size 1.27 1.27)
				)
			)
		)
		(duplicate_pad_numbers_are_jumpers no)
		(fp_line
			(start 0.7874 -0.4064)
			(end 0.7874 0.4064)
			(stroke
				(width 0.1524)
				(type default)
			)
			(layer "F.SilkS")
		)
		(fp_line
			(start -0.7874 -0.4064)
			(end 0.7874 -0.4064)
			(stroke
				(width 0.1524)
				(type default)
			)
			(layer "F.SilkS")
		)
		(fp_line
			(start 0.7874 0.4064)
			(end -0.7874 0.4064)
			(stroke
				(width 0.1524)
				(type default)
			)
			(layer "F.SilkS")
		)
		(fp_line
			(start -0.7874 0.4064)
			(end -0.7874 -0.4064)
			(stroke
				(width 0.1524)
				(type default)
			)
			(layer "F.SilkS")
		)
		(fp_line
			(start -0.12065 -0.305054)
			(end -0.12065 -0.2794)
			(stroke
				(width 0.1)
				(type default)
			)
			(layer "F.Fab")
		)
		(fp_line
			(start -0.67945 -0.305054)
			(end -0.12065 -0.305054)
			(stroke
				(width 0.1)
				(type default)
			)
			(layer "F.Fab")
		)
		(fp_line
			(start 0.67945 -0.3048)
			(end 0.67945 0.3048)
			(stroke
				(width 0.1)
				(type default)
			)
			(layer "F.Fab")
		)
		(fp_line
			(start 0.12065 -0.3048)
			(end 0.67945 -0.3048)
			(stroke
				(width 0.1)
				(type default)
			)
			(layer "F.Fab")
		)
		(fp_line
			(start 0.12065 -0.2794)
			(end 0.12065 -0.3048)
			(stroke
				(width 0.1)
				(type default)
			)
			(layer "F.Fab")
		)
		(fp_line
			(start -0.12065 -0.2794)
			(end 0.12065 -0.2794)
			(stroke
				(width 0.1)
				(type default)
			)
			(layer "F.Fab")
		)
		(fp_line
			(start 0.120396 0.2794)
			(end -0.12065 0.2794)
			(stroke
				(width 0.1)
				(type default)
			)
			(layer "F.Fab")
		)
		(fp_line
			(start -0.12065 0.2794)
			(end -0.12065 0.3048)
			(stroke
				(width 0.1)
				(type default)
			)
			(layer "F.Fab")
		)
		(fp_line
			(start 0.67945 0.3048)
			(end 0.120396 0.3048)
			(stroke
				(width 0.1)
				(type default)
			)
			(layer "F.Fab")
		)
		(fp_line
			(start 0.120396 0.3048)
			(end 0.120396 0.2794)
			(stroke
				(width 0.1)
				(type default)
			)
			(layer "F.Fab")
		)
		(fp_line
			(start -0.12065 0.3048)
			(end -0.67945 0.3048)
			(stroke
				(width 0.1)
				(type default)
			)
			(layer "F.Fab")
		)
		(fp_line
			(start -0.67945 0.3048)
			(end -0.67945 -0.305054)
			(stroke
				(width 0.1)
				(type default)
			)
			(layer "F.Fab")
		)
		(pad "1" smd circle
			(at -0.40005 0 90)
			(size 0 0)
			(layers "F.Cu" "F.Mask" "F.Paste")
			(net "P3V3_AUX")
		)
		(pad "2" smd circle
			(at 0.40005 0 90)
			(size 0 0)
			(layers "F.Cu" "F.Mask" "F.Paste")
			(net "SWB_HSC_EN")
		)
	)
	(footprint ""
		(layer "F.Cu")
		(at 125.453394 -408.517344 -90)
		(property "Reference" "C1519"
			(at 0 0 270)
			(layer "F.SilkS")
			(hide yes)
			(effects
				(font
					(size 1.27 1.27)
				)
			)
		)
		(property "Value" ""
			(at 0 0 270)
			(layer "F.Fab")
			(effects
				(font
					(size 1.27 1.27)
				)
			)
		)
		(duplicate_pad_numbers_are_jumpers no)
		(fp_line
			(start -0.299974 0.150114)
			(end -0.299974 -0.150114)
			(stroke
				(width 0.1)
				(type default)
			)
			(layer "F.Fab")
		)
		(fp_line
			(start 0.299974 0.150114)
			(end -0.299974 0.150114)
			(stroke
				(width 0.1)
				(type default)
			)
			(layer "F.Fab")
		)
		(fp_line
			(start -0.299974 -0.150114)
			(end 0.299974 -0.150114)
			(stroke
				(width 0.1)
				(type default)
			)
			(layer "F.Fab")
		)
		(fp_line
			(start 0.299974 -0.150114)
			(end 0.299974 0.150114)
			(stroke
				(width 0.1)
				(type default)
			)
			(layer "F.Fab")
		)
		(pad "1" smd rect
			(at -0.2667 0 270)
			(size 0.3048 0.381)
			(layers "F.Cu" "F.Mask" "F.Paste")
			(net "P5E_CPU1_PE3_TX_C_DP<14>")
		)
		(pad "2" smd rect
			(at 0.2667 0 270)
			(size 0.3048 0.381)
			(layers "F.Cu" "F.Mask" "F.Paste")
			(net "P5E_CPU1_PE3_TX_DP<14>")
		)
	)
	(footprint ""
		(layer "F.Cu")
		(at 430.277016 -101.97719 180)
		(property "Reference" "R3783"
			(at 0 0 180)
			(layer "F.SilkS")
			(hide yes)
			(effects
				(font
					(size 1.27 1.27)
				)
			)
		)
		(property "Value" ""
			(at 0 0 180)
			(layer "F.Fab")
			(effects
				(font
					(size 1.27 1.27)
				)
			)
		)
		(duplicate_pad_numbers_are_jumpers no)
		(fp_line
			(start 0.7874 0.4064)
			(end -0.7874 0.4064)
			(stroke
				(width 0.1524)
				(type default)
			)
			(layer "F.SilkS")
		)
		(fp_line
			(start 0.7874 -0.4064)
			(end 0.7874 0.4064)
			(stroke
				(width 0.1524)
				(type default)
			)
			(layer "F.SilkS")
		)
		(fp_line
			(start -0.7874 0.4064)
			(end -0.7874 -0.4064)
			(stroke
				(width 0.1524)
				(type default)
			)
			(layer "F.SilkS")
		)
		(fp_line
			(start -0.7874 -0.4064)
			(end 0.7874 -0.4064)
			(stroke
				(width 0.1524)
				(type default)
			)
			(layer "F.SilkS")
		)
		(fp_line
			(start 0.67945 0.3048)
			(end 0.120396 0.3048)
			(stroke
				(width 0.1)
				(type default)
			)
			(layer "F.Fab")
		)
		(fp_line
			(start 0.67945 -0.3048)
			(end 0.67945 0.3048)
			(stroke
				(width 0.1)
				(type default)
			)
			(layer "F.Fab")
		)
		(fp_line
			(start 0.12065 -0.2794)
			(end 0.12065 -0.3048)
			(stroke
				(width 0.1)
				(type default)
			)
			(layer "F.Fab")
		)
		(fp_line
			(start 0.12065 -0.3048)
			(end 0.67945 -0.3048)
			(stroke
				(width 0.1)
				(type default)
			)
			(layer "F.Fab")
		)
		(fp_line
			(start 0.120396 0.3048)
			(end 0.120396 0.2794)
			(stroke
				(width 0.1)
				(type default)
			)
			(layer "F.Fab")
		)
		(fp_line
			(start 0.120396 0.2794)
			(end -0.12065 0.2794)
			(stroke
				(width 0.1)
				(type default)
			)
			(layer "F.Fab")
		)
		(fp_line
			(start -0.12065 0.3048)
			(end -0.67945 0.3048)
			(stroke
				(width 0.1)
				(type default)
			)
			(layer "F.Fab")
		)
		(fp_line
			(start -0.12065 0.2794)
			(end -0.12065 0.3048)
			(stroke
				(width 0.1)
				(type default)
			)
			(layer "F.Fab")
		)
		(fp_line
			(start -0.12065 -0.2794)
			(end 0.12065 -0.2794)
			(stroke
				(width 0.1)
				(type default)
			)
			(layer "F.Fab")
		)
		(fp_line
			(start -0.12065 -0.305054)
			(end -0.12065 -0.2794)
			(stroke
				(width 0.1)
				(type default)
			)
			(layer "F.Fab")
		)
		(fp_line
			(start -0.67945 0.3048)
			(end -0.67945 -0.305054)
			(stroke
				(width 0.1)
				(type default)
			)
			(layer "F.Fab")
		)
		(fp_line
			(start -0.67945 -0.305054)
			(end -0.12065 -0.305054)
			(stroke
				(width 0.1)
				(type default)
			)
			(layer "F.Fab")
		)
		(pad "1" smd circle
			(at -0.40005 0 180)
			(size 0 0)
			(layers "F.Cu" "F.Mask" "F.Paste")
			(net "P3V3_AUX")
		)
		(pad "2" smd circle
			(at 0.40005 0 180)
			(size 0 0)
			(layers "F.Cu" "F.Mask" "F.Paste")
			(net "OCP_V3_1_P3V3_PWRGD")
		)
	)
)
